# S9S_MB_2U (Grand Teton) — schematic netlist excerpt (pin names and nets, part order shuffled) for the footprints in the layout excerpt that follows; sources: Cadence DE-HDL packaged netlist, KiCad conversion of 03242023_DA0F0TMBIJ0_F0T_Motherboard_J_brd_V01_OCP.brd

C822  Q_CAP_DIFFBUS  DIFF BUS_0.22UF 6.3V 20% X6S  pkg C0201  page 175 : \1\ = P5E_CPU1_PE1_TX_C_DN<7> ; \2\ = P5E_CPU1_PE1_TX_DN<7>
R1341  Q_RES  10K 1% CHIP  pkg 0402LF  page 201 : A = FM_ADR_COMPLETE ; B = GND

U154  74LVC1G07SE7  74LVC1G07SE-7 IC  pkg SOT353_0-65_2X1-25  page 202
  NC1  = NC_ESPI_PLD_R_EN_BUF
  A  = FM_ESPI_PLD_R1_EN
  GND  = GND
  Y  = FM_ESPI_PLD_R_EN_BUF
  VCC  = P3V3_AUX

(kicad_pcb
	(version 20260206)
	(generator "pcbnew")
	(generator_version "10.0")
	(general
		(thickness 1.6)
		(legacy_teardrops no)
	)
	(paper "A4")
	(title_block
		(title "03242023_DA0F0TMBIJ0_F0T_Motherboard_J_brd_V01_OCP.brd")
		(comment 1 "Grand Teton / footprints 3444-3446 of 6105")
	)
	(layers
		(0 "F.Cu" signal "TOP")
		(4 "In1.Cu" signal "GND")
		(6 "In2.Cu" signal "IN1")
		(8 "In3.Cu" signal "GND1")
		(10 "In4.Cu" signal "IN2")
		(12 "In5.Cu" signal "GND2")
		(14 "In6.Cu" signal "IN3")
		(16 "In7.Cu" signal "GND3")
		(18 "In8.Cu" signal "VCC")
		(20 "In9.Cu" signal "VCC1")
		(22 "In10.Cu" signal "GND4")
		(24 "In11.Cu" signal "IN4")
		(26 "In12.Cu" signal "GND5")
		(28 "In13.Cu" signal "IN5")
		(30 "In14.Cu" signal "GND6")
		(32 "In15.Cu" signal "IN6")
		(34 "In16.Cu" signal "GND7")
		(2 "B.Cu" signal "BOTTOM")
		(9 "F.Adhes" user "F.Adhesive")
		(11 "B.Adhes" user "B.Adhesive")
		(13 "F.Paste" user "Package Geometry/Pastemask Top")
		(15 "B.Paste" user "Package Geometry/Pastemask Bottom")
		(5 "F.SilkS" user "Ref Des/Silkscreen Top")
		(7 "B.SilkS" user "Ref Des/Silkscreen Bottom")
		(1 "F.Mask" user "Board Geometry/Soldermask Top")
		(3 "B.Mask" user "Board Geometry/Soldermask Bottom")
		(17 "Dwgs.User" user "User.Drawings")
		(19 "Cmts.User" user "User.Comments")
		(21 "Eco1.User" user "User.Eco1")
		(23 "Eco2.User" user "User.Eco2")
		(25 "Edge.Cuts" user "Board Geometry/Outline")
		(27 "Margin" user)
		(31 "F.CrtYd" user "Package Geometry/Place Bound Top")
		(29 "B.CrtYd" user "Package Geometry/Place Bound Bottom")
		(35 "F.Fab" user "Ref Des/Assembly Top")
		(33 "B.Fab" user "Ref Des/Assembly Bottom")
	)
	(footprint ""
		(layer "F.Cu")
		(at 304.034952 -54.012592 180)
		(property "Reference" "R1341"
			(at 0 0 180)
			(layer "F.SilkS")
			(hide yes)
			(effects
				(font
					(size 1.27 1.27)
				)
			)
		)
		(property "Value" ""
			(at 0 0 180)
			(layer "F.Fab")
			(effects
				(font
					(size 1.27 1.27)
				)
			)
		)
		(duplicate_pad_numbers_are_jumpers no)
		(fp_line
			(start 0.7874 0.4064)
			(end -0.7874 0.4064)
			(stroke
				(width 0.1524)
				(type default)
			)
			(layer "F.SilkS")
		)
		(fp_line
			(start 0.7874 -0.4064)
			(end 0.7874 0.4064)
			(stroke
				(width 0.1524)
				(type default)
			)
			(layer "F.SilkS")
		)
		(fp_line
			(start -0.7874 0.4064)
			(end -0.7874 -0.4064)
			(stroke
				(width 0.1524)
				(type default)
			)
			(layer "F.SilkS")
		)
		(fp_line
			(start -0.7874 -0.4064)
			(end 0.7874 -0.4064)
			(stroke
				(width 0.1524)
				(type default)
			)
			(layer "F.SilkS")
		)
		(fp_line
			(start 0.67945 0.3048)
			(end 0.120396 0.3048)
			(stroke
				(width 0.1)
				(type default)
			)
			(layer "F.Fab")
		)
		(fp_line
			(start 0.67945 -0.3048)
			(end 0.67945 0.3048)
			(stroke
				(width 0.1)
				(type default)
			)
			(layer "F.Fab")
		)
		(fp_line
			(start 0.12065 -0.2794)
			(end 0.12065 -0.3048)
			(stroke
				(width 0.1)
				(type default)
			)
			(layer "F.Fab")
		)
		(fp_line
			(start 0.12065 -0.3048)
			(end 0.67945 -0.3048)
			(stroke
				(width 0.1)
				(type default)
			)
			(layer "F.Fab")
		)
		(fp_line
			(start 0.120396 0.3048)
			(end 0.120396 0.2794)
			(stroke
				(width 0.1)
				(type default)
			)
			(layer "F.Fab")
		)
		(fp_line
			(start 0.120396 0.2794)
			(end -0.12065 0.2794)
			(stroke
				(width 0.1)
				(type default)
			)
			(layer "F.Fab")
		)
		(fp_line
			(start -0.12065 0.3048)
			(end -0.67945 0.3048)
			(stroke
				(width 0.1)
				(type default)
			)
			(layer "F.Fab")
		)
		(fp_line
			(start -0.12065 0.2794)
			(end -0.12065 0.3048)
			(stroke
				(width 0.1)
				(type default)
			)
			(layer "F.Fab")
		)
		(fp_line
			(start -0.12065 -0.2794)
			(end 0.12065 -0.2794)
			(stroke
				(width 0.1)
				(type default)
			)
			(layer "F.Fab")
		)
		(fp_line
			(start -0.12065 -0.305054)
			(end -0.12065 -0.2794)
			(stroke
				(width 0.1)
				(type default)
			)
			(layer "F.Fab")
		)
		(fp_line
			(start -0.67945 0.3048)
			(end -0.67945 -0.305054)
			(stroke
				(width 0.1)
				(type default)
			)
			(layer "F.Fab")
		)
		(fp_line
			(start -0.67945 -0.305054)
			(end -0.12065 -0.305054)
			(stroke
				(width 0.1)
				(type default)
			)
			(layer "F.Fab")
		)
		(pad "1" smd circle
			(at -0.40005 0 180)
			(size 0 0)
			(layers "F.Cu" "F.Mask" "F.Paste")
			(net "FM_ADR_COMPLETE")
		)
		(pad "2" smd circle
			(at 0.40005 0 180)
			(size 0 0)
			(layers "F.Cu" "F.Mask" "F.Paste")
			(net "GND")
		)
	)
	(footprint ""
		(layer "F.Cu")
		(at 330.848716 -13.985748)
		(property "Reference" "U154"
			(at 3.25374 0.200152 0)
			(unlocked yes)
			(layer "F.SilkS")
			(effects
				(font
					(size 0.7874 0.5842)
					(thickness 0.1524)
				)
				(justify left)
			)
		)
		(property "Value" ""
			(at 0 0 0)
			(layer "F.Fab")
			(effects
				(font
					(size 1.27 1.27)
				)
			)
		)
		(duplicate_pad_numbers_are_jumpers no)
		(fp_line
			(start -1.400048 1.100074)
			(end -1.400048 -1.100074)
			(stroke
				(width 0.1524)
				(type default)
			)
			(layer "F.SilkS")
		)
		(fp_line
			(start 1.400048 -1.100074)
			(end -1.400048 -1.100074)
			(stroke
				(width 0.1524)
				(type default)
			)
			(layer "F.SilkS")
		)
		(fp_line
			(start 1.400048 -1.100074)
			(end 1.400048 1.100074)
			(stroke
				(width 0.1524)
				(type default)
			)
			(layer "F.SilkS")
		)
		(fp_line
			(start 1.400048 1.100074)
			(end -1.400048 1.100074)
			(stroke
				(width 0.1524)
				(type default)
			)
			(layer "F.SilkS")
		)
		(fp_poly
			(pts
				(xy -0.812292 -1.192276) (xy -0.534416 -2.02565) (xy 0.021082 -1.470152)
			)
			(stroke
				(width 0)
				(type default)
			)
			(fill yes)
			(layer "F.SilkS")
		)
		(fp_line
			(start -0.674878 -1.100074)
			(end 0.674878 -1.100074)
			(stroke
				(width 0.1)
				(type default)
			)
			(layer "F.Fab")
		)
		(fp_line
			(start -0.674878 1.100074)
			(end -0.674878 -1.100074)
			(stroke
				(width 0.1)
				(type default)
			)
			(layer "F.Fab")
		)
		(fp_line
			(start 0.674878 -1.100074)
			(end 0.674878 1.100074)
			(stroke
				(width 0.1)
				(type default)
			)
			(layer "F.Fab")
		)
		(fp_line
			(start 0.674878 1.100074)
			(end -0.674878 1.100074)
			(stroke
				(width 0.1)
				(type default)
			)
			(layer "F.Fab")
		)
		(fp_poly
			(pts
				(xy -1.590548 -0.649986) (xy -2.606548 -1.157986) (xy -2.606548 -0.141986)
			)
			(stroke
				(width 0)
				(type default)
			)
			(fill yes)
			(layer "F.Fab")
		)
		(pad "1" smd rect
			(at -0.94996 -0.649986 270)
			(size 0.4318 0.6096)
			(layers "F.Cu" "F.Mask" "F.Paste")
			(net "NC_ESPI_PLD_R_EN_BUF")
		)
		(pad "2" smd rect
			(at -0.94996 0 270)
			(size 0.4318 0.6096)
			(layers "F.Cu" "F.Mask" "F.Paste")
			(net "FM_ESPI_PLD_R1_EN")
		)
		(pad "3" smd rect
			(at -0.94996 0.649986 270)
			(size 0.4318 0.6096)
			(layers "F.Cu" "F.Mask" "F.Paste")
			(net "GND")
		)
		(pad "4" smd rect
			(at 0.94996 0.649986 270)
			(size 0.4318 0.6096)
			(layers "F.Cu" "F.Mask" "F.Paste")
			(net "FM_ESPI_PLD_R_EN_BUF")
		)
		(pad "5" smd rect
			(at 0.94996 -0.649986 270)
			(size 0.4318 0.6096)
			(layers "F.Cu" "F.Mask" "F.Paste")
			(net "P3V3_AUX")
		)
	)
	(footprint ""
		(layer "F.Cu")
		(at 38.774878 -16.099536 90)
		(property "Reference" "C822"
			(at 0 0 90)
			(layer "F.SilkS")
			(hide yes)
			(effects
				(font
					(size 1.27 1.27)
				)
			)
		)
		(property "Value" ""
			(at 0 0 90)
			(layer "F.Fab")
			(effects
				(font
					(size 1.27 1.27)
				)
			)
		)
		(duplicate_pad_numbers_are_jumpers no)
		(fp_line
			(start 0.299974 -0.150114)
			(end 0.299974 0.150114)
			(stroke
				(width 0.1)
				(type default)
			)
			(layer "F.Fab")
		)
		(fp_line
			(start -0.299974 -0.150114)
			(end 0.299974 -0.150114)
			(stroke
				(width 0.1)
				(type default)
			)
			(layer "F.Fab")
		)
		(fp_line
			(start 0.299974 0.150114)
			(end -0.299974 0.150114)
			(stroke
				(width 0.1)
				(type default)
			)
			(layer "F.Fab")
		)
		(fp_line
			(start -0.299974 0.150114)
			(end -0.299974 -0.150114)
			(stroke
				(width 0.1)
				(type default)
			)
			(layer "F.Fab")
		)
		(pad "1" smd rect
			(at -0.2667 0 90)
			(size 0.3048 0.381)
			(layers "F.Cu" "F.Mask" "F.Paste")
			(net "P5E_CPU1_PE1_TX_C_DN<7>")
		)
		(pad "2" smd rect
			(at 0.2667 0 90)
			(size 0.3048 0.381)
			(layers "F.Cu" "F.Mask" "F.Paste")
			(net "P5E_CPU1_PE1_TX_DN<7>")
		)
	)
)
